# S9S_MB_2U (Grand Teton) — schematic netlist excerpt (pin names and nets, part order shuffled) for the footprints in the layout excerpt that follows; sources: Cadence DE-HDL packaged netlist, KiCad conversion of 03242023_DA0F0TMBIJ0_F0T_Motherboard_J_brd_V01_OCP.brd

R774  Q_RES  75 1% CHIP  pkg 0402LF  page 131 : A = JTAG_DBP_CPU_GTL_TCK ; B = GND
R1798  Q_RES  0 5% CHIP  pkg 0402LF  page 240 : A = ROT_P1_RST_IND_N_R ; B = ROT_P1_RST_IND_N

(kicad_pcb
	(version 20260206)
	(generator "pcbnew")
	(generator_version "10.0")
	(general
		(thickness 1.6)
		(legacy_teardrops no)
	)
	(paper "A4")
	(title_block
		(title "03242023_DA0F0TMBIJ0_F0T_Motherboard_J_brd_V01_OCP.brd")
		(comment 1 "Grand Teton / footprints 6098-6099 of 6105")
	)
	(layers
		(0 "F.Cu" signal "TOP")
		(4 "In1.Cu" signal "GND")
		(6 "In2.Cu" signal "IN1")
		(8 "In3.Cu" signal "GND1")
		(10 "In4.Cu" signal "IN2")
		(12 "In5.Cu" signal "GND2")
		(14 "In6.Cu" signal "IN3")
		(16 "In7.Cu" signal "GND3")
		(18 "In8.Cu" signal "VCC")
		(20 "In9.Cu" signal "VCC1")
		(22 "In10.Cu" signal "GND4")
		(24 "In11.Cu" signal "IN4")
		(26 "In12.Cu" signal "GND5")
		(28 "In13.Cu" signal "IN5")
		(30 "In14.Cu" signal "GND6")
		(32 "In15.Cu" signal "IN6")
		(34 "In16.Cu" signal "GND7")
		(2 "B.Cu" signal "BOTTOM")
		(9 "F.Adhes" user "F.Adhesive")
		(11 "B.Adhes" user "B.Adhesive")
		(13 "F.Paste" user "Package Geometry/Pastemask Top")
		(15 "B.Paste" user "Package Geometry/Pastemask Bottom")
		(5 "F.SilkS" user "Ref Des/Silkscreen Top")
		(7 "B.SilkS" user "Ref Des/Silkscreen Bottom")
		(1 "F.Mask" user "Board Geometry/Soldermask Top")
		(3 "B.Mask" user "Board Geometry/Soldermask Bottom")
		(17 "Dwgs.User" user "User.Drawings")
		(19 "Cmts.User" user "User.Comments")
		(21 "Eco1.User" user "User.Eco1")
		(23 "Eco2.User" user "User.Eco2")
		(25 "Edge.Cuts" user "Board Geometry/Outline")
		(27 "Margin" user)
		(31 "F.CrtYd" user "Package Geometry/Place Bound Top")
		(29 "B.CrtYd" user "Package Geometry/Place Bound Bottom")
		(35 "F.Fab" user "Ref Des/Assembly Top")
		(33 "B.Fab" user "Ref Des/Assembly Bottom")
	)
	(footprint ""
		(layer "B.Cu")
		(at 140.89888 -9.362948 -90)
		(property "Reference" "R1798"
			(at 0 0 90)
			(layer "B.SilkS")
			(hide yes)
			(effects
				(font
					(size 1.27 1.27)
				)
				(justify mirror)
			)
		)
		(property "Value" ""
			(at 0 0 90)
			(layer "B.Fab")
			(effects
				(font
					(size 1.27 1.27)
				)
				(justify mirror)
			)
		)
		(duplicate_pad_numbers_are_jumpers no)
		(fp_line
			(start -0.7874 0.4064)
			(end 0.7874 0.4064)
			(stroke
				(width 0.1524)
				(type default)
			)
			(layer "B.SilkS")
		)
		(fp_line
			(start 0.7874 0.4064)
			(end 0.7874 -0.4064)
			(stroke
				(width 0.1524)
				(type default)
			)
			(layer "B.SilkS")
		)
		(fp_line
			(start -0.7874 -0.4064)
			(end -0.7874 0.4064)
			(stroke
				(width 0.1524)
				(type default)
			)
			(layer "B.SilkS")
		)
		(fp_line
			(start 0.7874 -0.4064)
			(end -0.7874 -0.4064)
			(stroke
				(width 0.1524)
				(type default)
			)
			(layer "B.SilkS")
		)
		(fp_line
			(start -0.67945 0.3048)
			(end -0.120396 0.3048)
			(stroke
				(width 0.1)
				(type default)
			)
			(layer "B.Fab")
		)
		(fp_line
			(start -0.120396 0.3048)
			(end -0.120396 0.2794)
			(stroke
				(width 0.1)
				(type default)
			)
			(layer "B.Fab")
		)
		(fp_line
			(start 0.12065 0.3048)
			(end 0.67945 0.3048)
			(stroke
				(width 0.1)
				(type default)
			)
			(layer "B.Fab")
		)
		(fp_line
			(start 0.67945 0.3048)
			(end 0.67945 -0.305054)
			(stroke
				(width 0.1)
				(type default)
			)
			(layer "B.Fab")
		)
		(fp_line
			(start -0.120396 0.2794)
			(end 0.12065 0.2794)
			(stroke
				(width 0.1)
				(type default)
			)
			(layer "B.Fab")
		)
		(fp_line
			(start 0.12065 0.2794)
			(end 0.12065 0.3048)
			(stroke
				(width 0.1)
				(type default)
			)
			(layer "B.Fab")
		)
		(fp_line
			(start -0.12065 -0.2794)
			(end -0.12065 -0.3048)
			(stroke
				(width 0.1)
				(type default)
			)
			(layer "B.Fab")
		)
		(fp_line
			(start 0.12065 -0.2794)
			(end -0.12065 -0.2794)
			(stroke
				(width 0.1)
				(type default)
			)
			(layer "B.Fab")
		)
		(fp_line
			(start -0.67945 -0.3048)
			(end -0.67945 0.3048)
			(stroke
				(width 0.1)
				(type default)
			)
			(layer "B.Fab")
		)
		(fp_line
			(start -0.12065 -0.3048)
			(end -0.67945 -0.3048)
			(stroke
				(width 0.1)
				(type default)
			)
			(layer "B.Fab")
		)
		(fp_line
			(start 0.12065 -0.305054)
			(end 0.12065 -0.2794)
			(stroke
				(width 0.1)
				(type default)
			)
			(layer "B.Fab")
		)
		(fp_line
			(start 0.67945 -0.305054)
			(end 0.12065 -0.305054)
			(stroke
				(width 0.1)
				(type default)
			)
			(layer "B.Fab")
		)
		(pad "1" smd circle
			(at 0.40005 0 90)
			(size 0 0)
			(layers "B.Cu" "B.Mask" "B.Paste")
			(net "ROT_P1_RST_IND_N_R")
		)
		(pad "2" smd circle
			(at -0.40005 0 90)
			(size 0 0)
			(layers "B.Cu" "B.Mask" "B.Paste")
			(net "ROT_P1_RST_IND_N")
		)
	)
	(footprint ""
		(layer "B.Cu")
		(at 87.48776 -188.918088 90)
		(property "Reference" "R774"
			(at 0 0 90)
			(layer "B.SilkS")
			(hide yes)
			(effects
				(font
					(size 1.27 1.27)
				)
				(justify mirror)
			)
		)
		(property "Value" ""
			(at 0 0 90)
			(layer "B.Fab")
			(effects
				(font
					(size 1.27 1.27)
				)
				(justify mirror)
			)
		)
		(duplicate_pad_numbers_are_jumpers no)
		(fp_line
			(start 0.7874 -0.4064)
			(end -0.7874 -0.4064)
			(stroke
				(width 0.1524)
				(type default)
			)
			(layer "B.SilkS")
		)
		(fp_line
			(start -0.7874 -0.4064)
			(end -0.7874 0.4064)
			(stroke
				(width 0.1524)
				(type default)
			)
			(layer "B.SilkS")
		)
		(fp_line
			(start 0.7874 0.4064)
			(end 0.7874 -0.4064)
			(stroke
				(width 0.1524)
				(type default)
			)
			(layer "B.SilkS")
		)
		(fp_line
			(start -0.7874 0.4064)
			(end 0.7874 0.4064)
			(stroke
				(width 0.1524)
				(type default)
			)
			(layer "B.SilkS")
		)
		(fp_line
			(start 0.67945 -0.305054)
			(end 0.12065 -0.305054)
			(stroke
				(width 0.1)
				(type default)
			)
			(layer "B.Fab")
		)
		(fp_line
			(start 0.12065 -0.305054)
			(end 0.12065 -0.2794)
			(stroke
				(width 0.1)
				(type default)
			)
			(layer "B.Fab")
		)
		(fp_line
			(start -0.12065 -0.3048)
			(end -0.67945 -0.3048)
			(stroke
				(width 0.1)
				(type default)
			)
			(layer "B.Fab")
		)
		(fp_line
			(start -0.67945 -0.3048)
			(end -0.67945 0.3048)
			(stroke
				(width 0.1)
				(type default)
			)
			(layer "B.Fab")
		)
		(fp_line
			(start 0.12065 -0.2794)
			(end -0.12065 -0.2794)
			(stroke
				(width 0.1)
				(type default)
			)
			(layer "B.Fab")
		)
		(fp_line
			(start -0.12065 -0.2794)
			(end -0.12065 -0.3048)
			(stroke
				(width 0.1)
				(type default)
			)
			(layer "B.Fab")
		)
		(fp_line
			(start 0.12065 0.2794)
			(end 0.12065 0.3048)
			(stroke
				(width 0.1)
				(type default)
			)
			(layer "B.Fab")
		)
		(fp_line
			(start -0.120396 0.2794)
			(end 0.12065 0.2794)
			(stroke
				(width 0.1)
				(type default)
			)
			(layer "B.Fab")
		)
		(fp_line
			(start 0.67945 0.3048)
			(end 0.67945 -0.305054)
			(stroke
				(width 0.1)
				(type default)
			)
			(layer "B.Fab")
		)
		(fp_line
			(start 0.12065 0.3048)
			(end 0.67945 0.3048)
			(stroke
				(width 0.1)
				(type default)
			)
			(layer "B.Fab")
		)
		(fp_line
			(start -0.120396 0.3048)
			(end -0.120396 0.2794)
			(stroke
				(width 0.1)
				(type default)
			)
			(layer "B.Fab")
		)
		(fp_line
			(start -0.67945 0.3048)
			(end -0.120396 0.3048)
			(stroke
				(width 0.1)
				(type default)
			)
			(layer "B.Fab")
		)
		(pad "1" smd circle
			(at 0.40005 0 270)
			(size 0 0)
			(layers "B.Cu" "B.Mask" "B.Paste")
			(net "JTAG_DBP_CPU_GTL_TCK")
		)
		(pad "2" smd circle
			(at -0.40005 0 270)
			(size 0 0)
			(layers "B.Cu" "B.Mask" "B.Paste")
			(net "GND")
		)
	)
)
